# T6G (Grand Teton) — schematic netlist excerpt (pin names and nets, part order shuffled) for the footprints in the layout excerpt that follows; sources: Cadence DE-HDL packaged netlist, KiCad conversion of 04192023_DAF0TMB3IC0_F0TG_MB_C_brd_V02_OCP.brd

R10296  Q_RES  1K 1% CHIP  pkg 0402LF  page 145 : A = E1S_0_PWRDIS ; B = GND
R1704  Q_RES  10 1% CHIP  pkg 0402LF  page 103 : A = I3C_SPD_DDRAF_CPU1_SDA ; B = I3C_SPD_DDRF_CPU1_SDA

(kicad_pcb
	(version 20260206)
	(generator "pcbnew")
	(generator_version "10.0")
	(general
		(thickness 1.6)
		(legacy_teardrops no)
	)
	(paper "A4")
	(title_block
		(title "04192023_DAF0TMB3IC0_F0TG_MB_C_brd_V02_OCP.brd")
		(comment 1 "Grand Teton / footprints 5201-5203 of 8354")
	)
	(layers
		(0 "F.Cu" signal "TOP")
		(4 "In1.Cu" signal "GND")
		(6 "In2.Cu" signal "IN1")
		(8 "In3.Cu" signal "GND1")
		(10 "In4.Cu" signal "IN2")
		(12 "In5.Cu" signal "GND2")
		(14 "In6.Cu" signal "IN3")
		(16 "In7.Cu" signal "GND3")
		(18 "In8.Cu" signal "VCC")
		(20 "In9.Cu" signal "VCC1")
		(22 "In10.Cu" signal "GND4")
		(24 "In11.Cu" signal "IN4")
		(26 "In12.Cu" signal "GND5")
		(28 "In13.Cu" signal "IN5")
		(30 "In14.Cu" signal "GND6")
		(32 "In15.Cu" signal "IN6")
		(34 "In16.Cu" signal "GND7")
		(2 "B.Cu" signal "BOTTOM")
		(9 "F.Adhes" user "F.Adhesive")
		(11 "B.Adhes" user "B.Adhesive")
		(13 "F.Paste" user "Package Geometry/Pastemask Top")
		(15 "B.Paste" user "Package Geometry/Pastemask Bottom")
		(5 "F.SilkS" user "Ref Des/Silkscreen Top")
		(7 "B.SilkS" user "Ref Des/Silkscreen Bottom")
		(1 "F.Mask" user "Board Geometry/Soldermask Top")
		(3 "B.Mask" user "Board Geometry/Soldermask Bottom")
		(17 "Dwgs.User" user "User.Drawings")
		(19 "Cmts.User" user "User.Comments")
		(21 "Eco1.User" user "User.Eco1")
		(23 "Eco2.User" user "User.Eco2")
		(25 "Edge.Cuts" user "Board Geometry/Outline")
		(27 "Margin" user)
		(31 "F.CrtYd" user "Package Geometry/Place Bound Top")
		(29 "B.CrtYd" user "Package Geometry/Place Bound Bottom")
		(35 "F.Fab" user "Ref Des/Assembly Top")
		(33 "B.Fab" user "Ref Des/Assembly Bottom")
	)
	(footprint ""
		(layer "B.Cu")
		(at 236.20095 -51.209448)
		(property "Reference" "R10296"
			(at 0 0 0)
			(layer "B.SilkS")
			(hide yes)
			(effects
				(font
					(size 1.27 1.27)
				)
				(justify mirror)
			)
		)
		(property "Value" ""
			(at 0 0 0)
			(layer "B.Fab")
			(effects
				(font
					(size 1.27 1.27)
				)
				(justify mirror)
			)
		)
		(duplicate_pad_numbers_are_jumpers no)
		(fp_line
			(start -0.7874 -0.4064)
			(end -0.7874 0.4064)
			(stroke
				(width 0.1524)
				(type default)
			)
			(layer "B.SilkS")
		)
		(fp_line
			(start -0.7874 0.4064)
			(end 0.7874 0.4064)
			(stroke
				(width 0.1524)
				(type default)
			)
			(layer "B.SilkS")
		)
		(fp_line
			(start 0.7874 -0.4064)
			(end -0.7874 -0.4064)
			(stroke
				(width 0.1524)
				(type default)
			)
			(layer "B.SilkS")
		)
		(fp_line
			(start 0.7874 0.4064)
			(end 0.7874 -0.4064)
			(stroke
				(width 0.1524)
				(type default)
			)
			(layer "B.SilkS")
		)
		(fp_line
			(start -0.67945 -0.3048)
			(end -0.67945 0.3048)
			(stroke
				(width 0.1)
				(type default)
			)
			(layer "B.Fab")
		)
		(fp_line
			(start -0.67945 0.3048)
			(end -0.120396 0.3048)
			(stroke
				(width 0.1)
				(type default)
			)
			(layer "B.Fab")
		)
		(fp_line
			(start -0.12065 -0.3048)
			(end -0.67945 -0.3048)
			(stroke
				(width 0.1)
				(type default)
			)
			(layer "B.Fab")
		)
		(fp_line
			(start -0.12065 -0.2794)
			(end -0.12065 -0.3048)
			(stroke
				(width 0.1)
				(type default)
			)
			(layer "B.Fab")
		)
		(fp_line
			(start -0.120396 0.2794)
			(end 0.12065 0.2794)
			(stroke
				(width 0.1)
				(type default)
			)
			(layer "B.Fab")
		)
		(fp_line
			(start -0.120396 0.3048)
			(end -0.120396 0.2794)
			(stroke
				(width 0.1)
				(type default)
			)
			(layer "B.Fab")
		)
		(fp_line
			(start 0.12065 -0.305054)
			(end 0.12065 -0.2794)
			(stroke
				(width 0.1)
				(type default)
			)
			(layer "B.Fab")
		)
		(fp_line
			(start 0.12065 -0.2794)
			(end -0.12065 -0.2794)
			(stroke
				(width 0.1)
				(type default)
			)
			(layer "B.Fab")
		)
		(fp_line
			(start 0.12065 0.2794)
			(end 0.12065 0.3048)
			(stroke
				(width 0.1)
				(type default)
			)
			(layer "B.Fab")
		)
		(fp_line
			(start 0.12065 0.3048)
			(end 0.67945 0.3048)
			(stroke
				(width 0.1)
				(type default)
			)
			(layer "B.Fab")
		)
		(fp_line
			(start 0.67945 -0.305054)
			(end 0.12065 -0.305054)
			(stroke
				(width 0.1)
				(type default)
			)
			(layer "B.Fab")
		)
		(fp_line
			(start 0.67945 0.3048)
			(end 0.67945 -0.305054)
			(stroke
				(width 0.1)
				(type default)
			)
			(layer "B.Fab")
		)
		(pad "1" smd circle
			(at 0.40005 0 180)
			(size 0 0)
			(layers "B.Cu" "B.Mask" "B.Paste")
			(net "E1S_0_PWRDIS")
		)
		(pad "2" smd circle
			(at -0.40005 0 180)
			(size 0 0)
			(layers "B.Cu" "B.Mask" "B.Paste")
			(net "GND")
		)
	)
	(footprint ""
		(layer "B.Cu")
		(at 20.919186 -195.926964 180)
		(property "Reference" "R1704"
			(at 0 0 0)
			(layer "B.SilkS")
			(hide yes)
			(effects
				(font
					(size 1.27 1.27)
				)
				(justify mirror)
			)
		)
		(property "Value" ""
			(at 0 0 0)
			(layer "B.Fab")
			(effects
				(font
					(size 1.27 1.27)
				)
				(justify mirror)
			)
		)
		(duplicate_pad_numbers_are_jumpers no)
		(fp_line
			(start 0.7874 0.4064)
			(end 0.7874 -0.4064)
			(stroke
				(width 0.1524)
				(type default)
			)
			(layer "B.SilkS")
		)
		(fp_line
			(start 0.7874 -0.4064)
			(end -0.7874 -0.4064)
			(stroke
				(width 0.1524)
				(type default)
			)
			(layer "B.SilkS")
		)
		(fp_line
			(start -0.7874 0.4064)
			(end 0.7874 0.4064)
			(stroke
				(width 0.1524)
				(type default)
			)
			(layer "B.SilkS")
		)
		(fp_line
			(start -0.7874 -0.4064)
			(end -0.7874 0.4064)
			(stroke
				(width 0.1524)
				(type default)
			)
			(layer "B.SilkS")
		)
		(fp_line
			(start 0.67945 0.3048)
			(end 0.67945 -0.305054)
			(stroke
				(width 0.1)
				(type default)
			)
			(layer "B.Fab")
		)
		(fp_line
			(start 0.67945 -0.305054)
			(end 0.12065 -0.305054)
			(stroke
				(width 0.1)
				(type default)
			)
			(layer "B.Fab")
		)
		(fp_line
			(start 0.12065 0.3048)
			(end 0.67945 0.3048)
			(stroke
				(width 0.1)
				(type default)
			)
			(layer "B.Fab")
		)
		(fp_line
			(start 0.12065 0.2794)
			(end 0.12065 0.3048)
			(stroke
				(width 0.1)
				(type default)
			)
			(layer "B.Fab")
		)
		(fp_line
			(start 0.12065 -0.2794)
			(end -0.12065 -0.2794)
			(stroke
				(width 0.1)
				(type default)
			)
			(layer "B.Fab")
		)
		(fp_line
			(start 0.12065 -0.305054)
			(end 0.12065 -0.2794)
			(stroke
				(width 0.1)
				(type default)
			)
			(layer "B.Fab")
		)
		(fp_line
			(start -0.120396 0.3048)
			(end -0.120396 0.2794)
			(stroke
				(width 0.1)
				(type default)
			)
			(layer "B.Fab")
		)
		(fp_line
			(start -0.120396 0.2794)
			(end 0.12065 0.2794)
			(stroke
				(width 0.1)
				(type default)
			)
			(layer "B.Fab")
		)
		(fp_line
			(start -0.12065 -0.2794)
			(end -0.12065 -0.3048)
			(stroke
				(width 0.1)
				(type default)
			)
			(layer "B.Fab")
		)
		(fp_line
			(start -0.12065 -0.3048)
			(end -0.67945 -0.3048)
			(stroke
				(width 0.1)
				(type default)
			)
			(layer "B.Fab")
		)
		(fp_line
			(start -0.67945 0.3048)
			(end -0.120396 0.3048)
			(stroke
				(width 0.1)
				(type default)
			)
			(layer "B.Fab")
		)
		(fp_line
			(start -0.67945 -0.3048)
			(end -0.67945 0.3048)
			(stroke
				(width 0.1)
				(type default)
			)
			(layer "B.Fab")
		)
		(pad "1" smd circle
			(at 0.40005 0)
			(size 0 0)
			(layers "B.Cu" "B.Mask" "B.Paste")
			(net "I3C_SPD_DDRAF_CPU1_SDA")
		)
		(pad "2" smd circle
			(at -0.40005 0)
			(size 0 0)
			(layers "B.Cu" "B.Mask" "B.Paste")
			(net "I3C_SPD_DDRF_CPU1_SDA")
		)
	)
	(footprint ""
		(layer "B.Cu")
		(at 378.449078 -356.362508 180)
		(property "Reference" ""
			(at 0 0 0)
			(layer "B.SilkS")
			(hide yes)
			(effects
				(font
					(size 1.27 1.27)
				)
				(justify mirror)
			)
		)
		(property "Value" ""
			(at 0 0 0)
			(layer "B.Fab")
			(effects
				(font
					(size 1.27 1.27)
				)
				(justify mirror)
			)
		)
		(duplicate_pad_numbers_are_jumpers no)
		(pad "1" smd circle
			(at 0 0)
			(size 0.9906 0.9906)
			(layers "B.Cu" "B.Mask" "B.Paste")
			(net "Net_2233")
		)
		(zone
			(layer "B.Cu")
			(hatch none 0.5)
			(connect_pads
				(clearance 0)
			)
			(min_thickness 0.25)
			(keepout
				(tracks not_allowed)
				(vias allowed)
				(pads allowed)
				(copperpour not_allowed)
				(footprints allowed)
			)
			(placement
				(enabled no)
				(sheetname "")
			)
			(fill
				(thermal_gap 0.5)
				(thermal_bridge_width 0.5)
				(island_removal_mode 0)
			)
			(polygon
				(pts
					(arc
						(start 380.074678 -356.362508)
						(mid 376.823478 -356.362508)
						(end 380.074678 -356.362508)
					)
				)
			)
		)
	)
)
